# SCM (Grand Teton) — schematic netlist excerpt (pin names and nets, part order shuffled) for the footprints in the layout excerpt that follows; sources: Cadence DE-HDL packaged netlist, KiCad conversion of 12092022_DA0F0TMDCD0_F0T_Management_Board_D_brd_V3_OCP.brd

C51  Q_CAP  0.1UF 25V 10% X7R  pkg 0402  page 17 : A = P3V3_STBY_DACAV33 ; B = GND
C50  Q_CAP  0.1UF 25V 10% X7R  pkg 0402  page 17 : A = P1V0_STBY_RC_VCC10A ; B = GND

(kicad_pcb
	(version 20260206)
	(generator "pcbnew")
	(generator_version "10.0")
	(general
		(thickness 1.6)
		(legacy_teardrops no)
	)
	(paper "A4")
	(title_block
		(title "12092022_DA0F0TMDCD0_F0T_Management_Board_D_brd_V3_OCP.brd")
		(comment 1 "Grand Teton / footprints 1039-1040 of 1440")
	)
	(layers
		(0 "F.Cu" signal "TOP")
		(4 "In1.Cu" signal "GND")
		(6 "In2.Cu" signal "IN1")
		(8 "In3.Cu" signal "GND1")
		(10 "In4.Cu" signal "IN2")
		(12 "In5.Cu" signal "VCC")
		(14 "In6.Cu" signal "VCC1")
		(16 "In7.Cu" signal "IN3")
		(18 "In8.Cu" signal "GND2")
		(20 "In9.Cu" signal "IN4")
		(22 "In10.Cu" signal "GND3")
		(2 "B.Cu" signal "BOTTOM")
		(9 "F.Adhes" user "F.Adhesive")
		(11 "B.Adhes" user "B.Adhesive")
		(13 "F.Paste" user "Package Geometry/Pastemask Top")
		(15 "B.Paste" user "Package Geometry/Pastemask Bottom")
		(5 "F.SilkS" user "Ref Des/Silkscreen Top")
		(7 "B.SilkS" user "Ref Des/Silkscreen Bottom")
		(1 "F.Mask" user "Board Geometry/Soldermask Top")
		(3 "B.Mask" user "Board Geometry/Soldermask Bottom")
		(17 "Dwgs.User" user "User.Drawings")
		(19 "Cmts.User" user "User.Comments")
		(21 "Eco1.User" user "User.Eco1")
		(23 "Eco2.User" user "User.Eco2")
		(25 "Edge.Cuts" user "Board Geometry/Outline")
		(27 "Margin" user)
		(31 "F.CrtYd" user "Package Geometry/Place Bound Top")
		(29 "B.CrtYd" user "Package Geometry/Place Bound Bottom")
		(35 "F.Fab" user "Ref Des/Assembly Top")
		(33 "B.Fab" user "Ref Des/Assembly Bottom")
	)
	(footprint ""
		(layer "B.Cu")
		(at 56.94934 -51.95697)
		(property "Reference" "C50"
			(at 0 0 0)
			(layer "B.SilkS")
			(hide yes)
			(effects
				(font
					(size 1.27 1.27)
				)
				(justify mirror)
			)
		)
		(property "Value" ""
			(at 0 0 0)
			(layer "B.Fab")
			(effects
				(font
					(size 1.27 1.27)
				)
				(justify mirror)
			)
		)
		(duplicate_pad_numbers_are_jumpers no)
		(fp_line
			(start -0.7874 -0.4064)
			(end -0.7874 0.4064)
			(stroke
				(width 0.1524)
				(type default)
			)
			(layer "B.SilkS")
		)
		(fp_line
			(start -0.7874 0.4064)
			(end 0.7874 0.4064)
			(stroke
				(width 0.1524)
				(type default)
			)
			(layer "B.SilkS")
		)
		(fp_line
			(start 0.7874 -0.4064)
			(end -0.7874 -0.4064)
			(stroke
				(width 0.1524)
				(type default)
			)
			(layer "B.SilkS")
		)
		(fp_line
			(start 0.7874 0.4064)
			(end 0.7874 -0.4064)
			(stroke
				(width 0.1524)
				(type default)
			)
			(layer "B.SilkS")
		)
		(fp_line
			(start -0.67945 -0.3048)
			(end -0.67945 0.3048)
			(stroke
				(width 0.1)
				(type default)
			)
			(layer "B.Fab")
		)
		(fp_line
			(start -0.67945 0.3048)
			(end -0.120396 0.3048)
			(stroke
				(width 0.1)
				(type default)
			)
			(layer "B.Fab")
		)
		(fp_line
			(start -0.12065 -0.3048)
			(end -0.67945 -0.3048)
			(stroke
				(width 0.1)
				(type default)
			)
			(layer "B.Fab")
		)
		(fp_line
			(start -0.12065 -0.2794)
			(end -0.12065 -0.3048)
			(stroke
				(width 0.1)
				(type default)
			)
			(layer "B.Fab")
		)
		(fp_line
			(start -0.120396 0.2794)
			(end 0.12065 0.2794)
			(stroke
				(width 0.1)
				(type default)
			)
			(layer "B.Fab")
		)
		(fp_line
			(start -0.120396 0.3048)
			(end -0.120396 0.2794)
			(stroke
				(width 0.1)
				(type default)
			)
			(layer "B.Fab")
		)
		(fp_line
			(start 0.12065 -0.305054)
			(end 0.12065 -0.2794)
			(stroke
				(width 0.1)
				(type default)
			)
			(layer "B.Fab")
		)
		(fp_line
			(start 0.12065 -0.2794)
			(end -0.12065 -0.2794)
			(stroke
				(width 0.1)
				(type default)
			)
			(layer "B.Fab")
		)
		(fp_line
			(start 0.12065 0.2794)
			(end 0.12065 0.3048)
			(stroke
				(width 0.1)
				(type default)
			)
			(layer "B.Fab")
		)
		(fp_line
			(start 0.12065 0.3048)
			(end 0.67945 0.3048)
			(stroke
				(width 0.1)
				(type default)
			)
			(layer "B.Fab")
		)
		(fp_line
			(start 0.67945 -0.305054)
			(end 0.12065 -0.305054)
			(stroke
				(width 0.1)
				(type default)
			)
			(layer "B.Fab")
		)
		(fp_line
			(start 0.67945 0.3048)
			(end 0.67945 -0.305054)
			(stroke
				(width 0.1)
				(type default)
			)
			(layer "B.Fab")
		)
		(pad "1" smd circle
			(at 0.40005 0 180)
			(size 0 0)
			(layers "B.Cu" "B.Mask" "B.Paste")
			(net "P1V0_STBY_RC_VCC10A")
		)
		(pad "2" smd circle
			(at -0.40005 0 180)
			(size 0 0)
			(layers "B.Cu" "B.Mask" "B.Paste")
			(net "GND")
		)
	)
	(footprint ""
		(layer "B.Cu")
		(at 49.53 -54.1528 180)
		(property "Reference" "C51"
			(at 0 0 0)
			(layer "B.SilkS")
			(hide yes)
			(effects
				(font
					(size 1.27 1.27)
				)
				(justify mirror)
			)
		)
		(property "Value" ""
			(at 0 0 0)
			(layer "B.Fab")
			(effects
				(font
					(size 1.27 1.27)
				)
				(justify mirror)
			)
		)
		(duplicate_pad_numbers_are_jumpers no)
		(fp_line
			(start 0.7874 0.4064)
			(end 0.7874 -0.4064)
			(stroke
				(width 0.1524)
				(type default)
			)
			(layer "B.SilkS")
		)
		(fp_line
			(start 0.7874 -0.4064)
			(end -0.7874 -0.4064)
			(stroke
				(width 0.1524)
				(type default)
			)
			(layer "B.SilkS")
		)
		(fp_line
			(start -0.7874 0.4064)
			(end 0.7874 0.4064)
			(stroke
				(width 0.1524)
				(type default)
			)
			(layer "B.SilkS")
		)
		(fp_line
			(start -0.7874 -0.4064)
			(end -0.7874 0.4064)
			(stroke
				(width 0.1524)
				(type default)
			)
			(layer "B.SilkS")
		)
		(fp_line
			(start 0.67945 0.3048)
			(end 0.67945 -0.305054)
			(stroke
				(width 0.1)
				(type default)
			)
			(layer "B.Fab")
		)
		(fp_line
			(start 0.67945 -0.305054)
			(end 0.12065 -0.305054)
			(stroke
				(width 0.1)
				(type default)
			)
			(layer "B.Fab")
		)
		(fp_line
			(start 0.12065 0.3048)
			(end 0.67945 0.3048)
			(stroke
				(width 0.1)
				(type default)
			)
			(layer "B.Fab")
		)
		(fp_line
			(start 0.12065 0.2794)
			(end 0.12065 0.3048)
			(stroke
				(width 0.1)
				(type default)
			)
			(layer "B.Fab")
		)
		(fp_line
			(start 0.12065 -0.2794)
			(end -0.12065 -0.2794)
			(stroke
				(width 0.1)
				(type default)
			)
			(layer "B.Fab")
		)
		(fp_line
			(start 0.12065 -0.305054)
			(end 0.12065 -0.2794)
			(stroke
				(width 0.1)
				(type default)
			)
			(layer "B.Fab")
		)
		(fp_line
			(start -0.120396 0.3048)
			(end -0.120396 0.2794)
			(stroke
				(width 0.1)
				(type default)
			)
			(layer "B.Fab")
		)
		(fp_line
			(start -0.120396 0.2794)
			(end 0.12065 0.2794)
			(stroke
				(width 0.1)
				(type default)
			)
			(layer "B.Fab")
		)
		(fp_line
			(start -0.12065 -0.2794)
			(end -0.12065 -0.3048)
			(stroke
				(width 0.1)
				(type default)
			)
			(layer "B.Fab")
		)
		(fp_line
			(start -0.12065 -0.3048)
			(end -0.67945 -0.3048)
			(stroke
				(width 0.1)
				(type default)
			)
			(layer "B.Fab")
		)
		(fp_line
			(start -0.67945 0.3048)
			(end -0.120396 0.3048)
			(stroke
				(width 0.1)
				(type default)
			)
			(layer "B.Fab")
		)
		(fp_line
			(start -0.67945 -0.3048)
			(end -0.67945 0.3048)
			(stroke
				(width 0.1)
				(type default)
			)
			(layer "B.Fab")
		)
		(pad "1" smd circle
			(at 0.40005 0)
			(size 0 0)
			(layers "B.Cu" "B.Mask" "B.Paste")
			(net "P3V3_STBY_DACAV33")
		)
		(pad "2" smd circle
			(at -0.40005 0)
			(size 0 0)
			(layers "B.Cu" "B.Mask" "B.Paste")
			(net "GND")
		)
	)
)
